# S9S_MB_2U (Grand Teton) — schematic netlist excerpt (pin names and nets, part order shuffled) for the footprints in the layout excerpt that follows; sources: Cadence DE-HDL packaged netlist, KiCad conversion of 03242023_DA0F0TMBIJ0_F0T_Motherboard_J_brd_V01_OCP.brd

J31  SCONN288_ADR50017P130CC  SCONN288_ADR50017-P130CC IO  pkg DDR288S_1-1VXB  page 112
  VIN_BULK0  = P12V_S3_AUX_CPU1_NVDIMM
  RFU0  = TP_CHH_CPU1_DIMM1_FRU_0
  VIN_MGMT  = P3V3_AUX
  HSCL  = I3C_SPD_DDREFGH_CPU1_LVC1_SCL_6
  HSDA  = I3C_SPD_DDREFGH_CPU1_LVC1_SDA
  VSS0  = GND
  DQ0_A  = M_H_CPU1_SA_DQ<0>
  VSS1  = GND
  DQ1_A  = M_H_CPU1_SA_DQ<1>
  VSS2  = GND
  DQS0_A_T  = M_H_CPU1_SA_DQS_DP<0>
  DQS0_A_C  = M_H_CPU1_SA_DQS_DN<0>
  VSS3  = GND
  DQ4_A  = M_H_CPU1_SA_DQ<4>
  VSS4  = GND
  DQ5_A  = M_H_CPU1_SA_DQ<5>
  VSS5  = GND
  DQ8_A  = M_H_CPU1_SA_DQ<8>
  VSS6  = GND
  DQ9_A  = M_H_CPU1_SA_DQ<9>
  VSS7  = GND
  DQS1_A_T  = M_H_CPU1_SA_DQS_DP<1>
  DQS1_A_C  = M_H_CPU1_SA_DQS_DN<1>
  VSS8  = GND
  DQ12_A  = M_H_CPU1_SA_DQ<12>
  VSS9  = GND
  DQ13_A  = M_H_CPU1_SA_DQ<13>
  VSS10  = GND
  DQ16_A  = M_H_CPU1_SA_DQ<16>
  VSS11  = GND
  DQ17_A  = M_H_CPU1_SA_DQ<17>
  VSS12  = GND
  DQS2_A_T  = M_H_CPU1_SA_DQS_DP<2>
  DQS2_A_C  = M_H_CPU1_SA_DQS_DN<2>
  VSS13  = GND
  DQ20_A  = M_H_CPU1_SA_DQ<20>
  VSS14  = GND
  DQ21_A  = M_H_CPU1_SA_DQ<21>
  VSS15  = GND
  DQ24_A  = M_H_CPU1_SA_DQ<24>
  VSS16  = GND
  DQ25_A  = M_H_CPU1_SA_DQ<25>
  VSS17  = GND
  DQS3_A_T  = M_H_CPU1_SA_DQS_DP<3>
  DQS3_A_C  = M_H_CPU1_SA_DQS_DN<3>
  VSS18  = GND
  DQ28_A  = M_H_CPU1_SA_DQ<28>
  VSS19  = GND
  DQ29_A  = M_H_CPU1_SA_DQ<29>
  VSS20  = GND
  CB0_A  = M_H_CPU1_SA_CB<0>
  VSS21  = GND
  CB1_A  = M_H_CPU1_SA_CB<1>
  VSS22  = GND
  DQS4_A_T  = M_H_CPU1_SA_DQS_DP<4>
  DQS4_A_C  = M_H_CPU1_SA_DQS_DN<4>
  VSS23  = GND
  CB4_A  = M_H_CPU1_SA_CB<4>
  VSS24  = GND
  CB5_A  = M_H_CPU1_SA_CB<5>
  VSS25  = GND
  ALERT_N  = M_H_CPU1_ALERT_N
  VSS26  = GND
  CS0_A_N  = M_H_CPU1_SA_CS_N<0>
  VSS27  = GND
  CA0_A  = M_H_CPU1_SA_CA<0>
  VSS28  = GND
  CA2_A  = M_H_CPU1_SA_CA<2>
  VSS29  = GND
  CA4_A  = M_H_CPU1_SA_CA<4>
  VSS30  = GND
  CA6_A  = M_H_CPU1_SA_CA<6>
  VSS31  = GND
  PAR_A  = M_H_CPU1_SA_PAR
  VSS32  = GND
  CA0_B  = M_H_CPU1_SB_CA<0>
  VSS33  = GND
  CA2_B  = M_H_CPU1_SB_CA<2>
  VSS34  = GND
  CA4_B  = M_H_CPU1_SB_CA<4>
  VSS35  = GND
  CA6_B  = M_H_CPU1_SB_CA<6>
  VSS36  = GND
  CS0_B_N  = M_H_CPU1_SB_CS_N<0>
  VSS37  = GND
  \lbd||rsp_a_n\  = M_H_CPU1_SA_RSP<0>
  \lbs||rsp_b_n\  = M_H_CPU1_SB_RSP<0>
  VSS38  = GND
  CB4_B  = M_H_CPU1_SB_CB<4>
  VSS39  = GND
  CB5_B  = M_H_CPU1_SB_CB<5>
  VSS40  = GND
  \dqs9_b_t||tdqs9_b_t||dbi4_b_n\  = M_H_CPU1_SB_DQS_DP<9>
  \dqs9_b_c||tdqs9_b_c\  = M_H_CPU1_SB_DQS_DN<9>
  VSS41  = GND
  CB0_B  = M_H_CPU1_SB_CB<0>
  VSS42  = GND
  CB1_B  = M_H_CPU1_SB_CB<1>
  VSS43  = GND
  DQ0_B  = M_H_CPU1_SB_DQ<0>
  VSS44  = GND
  DQ1_B  = M_H_CPU1_SB_DQ<1>
  VSS45  = GND
  DQS0_B_T  = M_H_CPU1_SB_DQS_DP<0>
  DQS0_B_C  = M_H_CPU1_SB_DQS_DN<0>
  VSS46  = GND
  DQ4_B  = M_H_CPU1_SB_DQ<4>
  VSS47  = GND
  DQ5_B  = M_H_CPU1_SB_DQ<5>
  VSS48  = GND
  DQ8_B  = M_H_CPU1_SB_DQ<8>
  VSS49  = GND
  DQ9_B  = M_H_CPU1_SB_DQ<9>
  VSS50  = GND
  DQS1_B_T  = M_H_CPU1_SB_DQS_DP<1>
  DQS1_B_C  = M_H_CPU1_SB_DQS_DN<1>
  VSS51  = GND
  DQ12_B  = M_H_CPU1_SB_DQ<12>
  VSS52  = GND
  DQ13_B  = M_H_CPU1_SB_DQ<13>
  VSS53  = GND
  DQ16_B  = M_H_CPU1_SB_DQ<16>
  VSS54  = GND
  DQ17_B  = M_H_CPU1_SB_DQ<17>
  VSS55  = GND
  DQS2_B_T  = M_H_CPU1_SB_DQS_DP<2>
  DQS2_B_C  = M_H_CPU1_SB_DQS_DN<2>
  VSS56  = GND
  DQ20_B  = M_H_CPU1_SB_DQ<20>
  VSS57  = GND
  DQ21_B  = M_H_CPU1_SB_DQ<21>
  VSS58  = GND
  DQ24_B  = M_H_CPU1_SB_DQ<24>
  VSS59  = GND
  DQ25_B  = M_H_CPU1_SB_DQ<25>
  VSS60  = GND
  DQS3_B_T  = M_H_CPU1_SB_DQS_DP<3>
  DQS3_B_C  = M_H_CPU1_SB_DQS_DN<3>
  VSS61  = GND
  DQ28_B  = M_H_CPU1_SB_DQ<28>
  VSS62  = GND
  DQ29_B  = M_H_CPU1_SB_DQ<29>
  VSS63  = GND
  RFU1  = TP_CHH_CPU1_DIMM1_FRU_1
  VIN_BULK1  = P12V_S3_AUX_CPU1_NVDIMM
  VIN_BULK2  = P12V_S3_AUX_CPU1_NVDIMM
  \pwr_good||fail_n\  = PWRGD_CHH_CPU1_DIMM1
  HSA  = PD_CHH_CPU1_DIMM1_SAA
  RFU2  = TP_CHH_CPU1_DIMM1_FRU_2
  RFU3  = TP_CHH_CPU1_DIMM1_FRU_3
  VSS64  = GND
  DQ2_A  = M_H_CPU1_SA_DQ<2>
  VSS65  = GND
  DQ3_A  = M_H_CPU1_SA_DQ<3>
  VSS66  = GND
  \dqs5_a_c||tdqs5_a_c||dqs5_a_t||tdqs5_a_t\  = M_H_CPU1_SA_DQS_DN<5>
  \dqs5_a_t||tdqs5_a_t\  = M_H_CPU1_SA_DQS_DP<5>
  VSS67  = GND
  DQ6_A  = M_H_CPU1_SA_DQ<6>
  VSS68  = GND
  DQ7_A  = M_H_CPU1_SA_DQ<7>
  VSS69  = GND
  DQ10_A  = M_H_CPU1_SA_DQ<10>
  VSS70  = GND
  DQ11_A  = M_H_CPU1_SA_DQ<11>
  VSS71  = GND
  \dqs6_a_c||tdqs6_a_c||dqs6_a_t||tdqs6_a_t\  = M_H_CPU1_SA_DQS_DN<6>
  \dqs6_a_t||tdqs6_a_t\  = M_H_CPU1_SA_DQS_DP<6>
  VSS72  = GND
  DQ14_A  = M_H_CPU1_SA_DQ<14>
  VSS73  = GND
  DQ15_A  = M_H_CPU1_SA_DQ<15>
  VSS74  = GND
  DQ18_A  = M_H_CPU1_SA_DQ<18>
  VSS75  = GND
  DQ19_A  = M_H_CPU1_SA_DQ<19>
  VSS76  = GND
  \dqs7_a_c||tdqs7_a_c\  = M_H_CPU1_SA_DQS_DN<7>
  \dqs7_a_t||tdqs7_a_t\  = M_H_CPU1_SA_DQS_DP<7>
  VSS77  = GND
  DQ22_A  = M_H_CPU1_SA_DQ<22>
  VSS78  = GND
  DQ23_A  = M_H_CPU1_SA_DQ<23>
  VSS79  = GND
  DQ26_A  = M_H_CPU1_SA_DQ<26>
  VSS80  = GND
  DQ27_A  = M_H_CPU1_SA_DQ<27>
  VSS81  = GND
  \dqs8_a_c||tdqs8_a_c\  = M_H_CPU1_SA_DQS_DN<8>
  \dqs8_a_t||tdqs8_a_t\  = M_H_CPU1_SA_DQS_DP<8>
  VSS82  = GND
  DQ30_A  = M_H_CPU1_SA_DQ<30>
  VSS83  = GND
  DQ31_A  = M_H_CPU1_SA_DQ<31>
  VSS84  = GND
  CB2_A  = M_H_CPU1_SA_CB<2>
  VSS85  = GND
  CB3_A  = M_H_CPU1_SA_CB<3>
  VSS86  = GND
  \dqs9_a_c||tdqs9_a_c\  = M_H_CPU1_SA_DQS_DN<9>
  \dqs9_a_t||tdqs9_a_t\  = M_H_CPU1_SA_DQS_DP<9>
  VSS87  = GND
  CB6_A  = M_H_CPU1_SA_CB<6>
  VSS88  = GND
  CB7_A  = M_H_CPU1_SA_CB<7>
  VSS89  = GND
  RESET_N  = RST_M_GH_CPU1_FPGA_N
  VSS90  = GND
  CS1_A_N  = M_H_CPU1_SA_CS_N<1>
  VSS91  = GND
  CA1_A  = M_H_CPU1_SA_CA<1>
  VSS92  = GND
  CA3_A  = M_H_CPU1_SA_CA<3>
  VSS93  = GND
  CA5_A  = M_H_CPU1_SA_CA<5>
  VSS94  = GND
  CK_T  = M_H_CPU1_CLK_DP<0>
  CK_C  = M_H_CPU1_CLK_DN<0>
  VSS95  = GND
  RFU4  = TP_CHH_CPU1_DIMM1_FRU_4
  CA1_B  = M_H_CPU1_SB_CA<1>
  VSS96  = GND
  CA3_B  = M_H_CPU1_SB_CA<3>
  VSS97  = GND
  CA5_B  = M_H_CPU1_SB_CA<5>
  VSS98  = GND
  PAR_B  = M_H_CPU1_SB_PAR
  VSS99  = GND
  CS1_B_N  = M_H_CPU1_SB_CS_N<1>
  VSS100  = GND
  RFU5  = TP_CHH_CPU1_DIMM1_FRU_5
  RFU6  = TP_CHH_CPU1_DIMM1_FRU_6
  VSS101  = GND
  CB6_B  = M_H_CPU1_SB_CB<6>
  VSS102  = GND
  CB7_B  = M_H_CPU1_SB_CB<7>
  VSS103  = GND
  DQS4_B_C  = M_H_CPU1_SB_DQS_DN<4>
  DQS4_B_T  = M_H_CPU1_SB_DQS_DP<4>
  VSS104  = GND
  CB2_B  = M_H_CPU1_SB_CB<2>
  VSS105  = GND
  CB3_B  = M_H_CPU1_SB_CB<3>
  VSS106  = GND
  DQ2_B  = M_H_CPU1_SB_DQ<2>
  VSS107  = GND
  DQ3_B  = M_H_CPU1_SB_DQ<3>
  VSS108  = GND
  \dqs5_b_c||tdqs5_b_c\  = M_H_CPU1_SB_DQS_DN<5>
  \dqs5_b_t||tdqs5_b_t\  = M_H_CPU1_SB_DQS_DP<5>
  VSS109  = GND
  DQ6_B  = M_H_CPU1_SB_DQ<6>
  VSS110  = GND
  DQ7_B  = M_H_CPU1_SB_DQ<7>
  VSS111  = GND
  DQ10_B  = M_H_CPU1_SB_DQ<10>
  VSS112  = GND
  DQ11_B  = M_H_CPU1_SB_DQ<11>
  VSS113  = GND
  \dqs6_b_c||tdqs6_b_c\  = M_H_CPU1_SB_DQS_DN<6>
  \dqs6_b_t||tdqs6_b_t\  = M_H_CPU1_SB_DQS_DP<6>
  VSS114  = GND
  DQ14_B  = M_H_CPU1_SB_DQ<14>
  VSS115  = GND
  DQ15_B  = M_H_CPU1_SB_DQ<15>
  VSS116  = GND
  DQ18_B  = M_H_CPU1_SB_DQ<18>
  VSS117  = GND
  DQ19_B  = M_H_CPU1_SB_DQ<19>
  VSS118  = GND
  \dqs7_b_c||tdqs7_b_c\  = M_H_CPU1_SB_DQS_DN<7>
  \dqs7_b_t||tdqs7_b_t\  = M_H_CPU1_SB_DQS_DP<7>
  VSS119  = GND
  DQ22_B  = M_H_CPU1_SB_DQ<22>
  VSS120  = GND
  DQ23_B  = M_H_CPU1_SB_DQ<23>
  VSS121  = GND
  DQ26_B  = M_H_CPU1_SB_DQ<26>
  VSS122  = GND
  DQ27_B  = M_H_CPU1_SB_DQ<27>
  VSS123  = GND
  \dqs8_b_c||tdqs8_b_c\  = M_H_CPU1_SB_DQS_DN<8>
  \dqs8_b_t||tdqs8_b_t\  = M_H_CPU1_SB_DQS_DP<8>
  VSS124  = GND
  DQ30_B  = M_H_CPU1_SB_DQ<30>
  VSS125  = GND
  DQ31_B  = M_H_CPU1_SB_DQ<31>
  VSS126  = GND
  G1  = GND
  G2  = GND
  G3  = GND

(kicad_pcb
	(version 20260206)
	(generator "pcbnew")
	(generator_version "10.0")
	(general
		(thickness 1.6)
		(legacy_teardrops no)
	)
	(paper "A4")
	(title_block
		(title "03242023_DA0F0TMBIJ0_F0T_Motherboard_J_brd_V01_OCP.brd")
		(comment 1 "Grand Teton / footprint 3900 of 6105 (J31), pads 92-137 of 291")
	)
	(layers
		(0 "F.Cu" signal "TOP")
		(4 "In1.Cu" signal "GND")
		(6 "In2.Cu" signal "IN1")
		(8 "In3.Cu" signal "GND1")
		(10 "In4.Cu" signal "IN2")
		(12 "In5.Cu" signal "GND2")
		(14 "In6.Cu" signal "IN3")
		(16 "In7.Cu" signal "GND3")
		(18 "In8.Cu" signal "VCC")
		(20 "In9.Cu" signal "VCC1")
		(22 "In10.Cu" signal "GND4")
		(24 "In11.Cu" signal "IN4")
		(26 "In12.Cu" signal "GND5")
		(28 "In13.Cu" signal "IN5")
		(30 "In14.Cu" signal "GND6")
		(32 "In15.Cu" signal "IN6")
		(34 "In16.Cu" signal "GND7")
		(2 "B.Cu" signal "BOTTOM")
		(9 "F.Adhes" user "F.Adhesive")
		(11 "B.Adhes" user "B.Adhesive")
		(13 "F.Paste" user "Package Geometry/Pastemask Top")
		(15 "B.Paste" user "Package Geometry/Pastemask Bottom")
		(5 "F.SilkS" user "Ref Des/Silkscreen Top")
		(7 "B.SilkS" user "Ref Des/Silkscreen Bottom")
		(1 "F.Mask" user "Board Geometry/Soldermask Top")
		(3 "B.Mask" user "Board Geometry/Soldermask Bottom")
		(17 "Dwgs.User" user "User.Drawings")
		(19 "Cmts.User" user "User.Comments")
		(21 "Eco1.User" user "User.Eco1")
		(23 "Eco2.User" user "User.Eco2")
		(25 "Edge.Cuts" user "Board Geometry/Outline")
		(27 "Margin" user)
		(31 "F.CrtYd" user "Package Geometry/Place Bound Top")
		(29 "B.CrtYd" user "Package Geometry/Place Bound Bottom")
		(35 "F.Fab" user "Ref Des/Assembly Top")
		(33 "B.Fab" user "Ref Des/Assembly Bottom")
	)
	(footprint ""
		(layer "F.Cu")
		(at 213.66988 -258.091686)
		(property "Reference" "J31"
			(at -3.683 -81.702148 0)
			(unlocked yes)
			(layer "F.SilkS")
			(effects
				(font
					(size 0.7874 0.5842)
					(thickness 0.1524)
				)
				(justify left)
			)
		)
		(property "Value" ""
			(at 0 0 0)
			(layer "F.Fab")
			(effects
				(font
					(size 1.27 1.27)
				)
			)
		)
		(duplicate_pad_numbers_are_jumpers no)
		(pad "92" smd rect
			(at -2.050034 19.12493 270)
			(size 0.519938 1.4986)
			(layers "F.Cu" "F.Mask" "F.Paste")
			(net "GND")
		)
		(pad "93" smd rect
			(at -2.050034 19.975068 270)
			(size 0.519938 1.4986)
			(layers "F.Cu" "F.Mask" "F.Paste")
			(net "M_H_CPU1_SB_DQS_DP<9>")
		)
		(pad "94" smd rect
			(at -2.050034 20.824952 270)
			(size 0.519938 1.4986)
			(layers "F.Cu" "F.Mask" "F.Paste")
			(net "M_H_CPU1_SB_DQS_DN<9>")
		)
		(pad "95" smd rect
			(at -2.050034 21.67509 270)
			(size 0.519938 1.4986)
			(layers "F.Cu" "F.Mask" "F.Paste")
			(net "GND")
		)
		(pad "96" smd rect
			(at -2.050034 22.524974 270)
			(size 0.519938 1.4986)
			(layers "F.Cu" "F.Mask" "F.Paste")
			(net "M_H_CPU1_SB_CB<0>")
		)
		(pad "97" smd rect
			(at -2.050034 23.375112 270)
			(size 0.519938 1.4986)
			(layers "F.Cu" "F.Mask" "F.Paste")
			(net "GND")
		)
		(pad "98" smd rect
			(at -2.050034 24.224996 270)
			(size 0.519938 1.4986)
			(layers "F.Cu" "F.Mask" "F.Paste")
			(net "M_H_CPU1_SB_CB<1>")
		)
		(pad "99" smd rect
			(at -2.050034 25.07488 270)
			(size 0.519938 1.4986)
			(layers "F.Cu" "F.Mask" "F.Paste")
			(net "GND")
		)
		(pad "100" smd rect
			(at -2.050034 25.925018 270)
			(size 0.519938 1.4986)
			(layers "F.Cu" "F.Mask" "F.Paste")
			(net "M_H_CPU1_SB_DQ<0>")
		)
		(pad "101" smd rect
			(at -2.050034 26.774902 270)
			(size 0.519938 1.4986)
			(layers "F.Cu" "F.Mask" "F.Paste")
			(net "GND")
		)
		(pad "102" smd rect
			(at -2.050034 27.62504 270)
			(size 0.519938 1.4986)
			(layers "F.Cu" "F.Mask" "F.Paste")
			(net "M_H_CPU1_SB_DQ<1>")
		)
		(pad "103" smd rect
			(at -2.050034 28.474924 270)
			(size 0.519938 1.4986)
			(layers "F.Cu" "F.Mask" "F.Paste")
			(net "GND")
		)
		(pad "104" smd rect
			(at -2.050034 29.325062 270)
			(size 0.519938 1.4986)
			(layers "F.Cu" "F.Mask" "F.Paste")
			(net "M_H_CPU1_SB_DQS_DP<0>")
		)
		(pad "105" smd rect
			(at -2.050034 30.174946 270)
			(size 0.519938 1.4986)
			(layers "F.Cu" "F.Mask" "F.Paste")
			(net "M_H_CPU1_SB_DQS_DN<0>")
		)
		(pad "106" smd rect
			(at -2.050034 31.025084 270)
			(size 0.519938 1.4986)
			(layers "F.Cu" "F.Mask" "F.Paste")
			(net "GND")
		)
		(pad "107" smd rect
			(at -2.050034 31.874968 270)
			(size 0.519938 1.4986)
			(layers "F.Cu" "F.Mask" "F.Paste")
			(net "M_H_CPU1_SB_DQ<4>")
		)
		(pad "108" smd rect
			(at -2.050034 32.725106 270)
			(size 0.519938 1.4986)
			(layers "F.Cu" "F.Mask" "F.Paste")
			(net "GND")
		)
		(pad "109" smd rect
			(at -2.050034 33.57499 270)
			(size 0.519938 1.4986)
			(layers "F.Cu" "F.Mask" "F.Paste")
			(net "M_H_CPU1_SB_DQ<5>")
		)
		(pad "110" smd rect
			(at -2.050034 34.425128 270)
			(size 0.519938 1.4986)
			(layers "F.Cu" "F.Mask" "F.Paste")
			(net "GND")
		)
		(pad "111" smd rect
			(at -2.050034 35.275012 270)
			(size 0.519938 1.4986)
			(layers "F.Cu" "F.Mask" "F.Paste")
			(net "M_H_CPU1_SB_DQ<8>")
		)
		(pad "112" smd rect
			(at -2.050034 36.124896 270)
			(size 0.519938 1.4986)
			(layers "F.Cu" "F.Mask" "F.Paste")
			(net "GND")
		)
		(pad "113" smd rect
			(at -2.050034 36.975034 270)
			(size 0.519938 1.4986)
			(layers "F.Cu" "F.Mask" "F.Paste")
			(net "M_H_CPU1_SB_DQ<9>")
		)
		(pad "114" smd rect
			(at -2.050034 37.824918 270)
			(size 0.519938 1.4986)
			(layers "F.Cu" "F.Mask" "F.Paste")
			(net "GND")
		)
		(pad "115" smd rect
			(at -2.050034 38.675056 270)
			(size 0.519938 1.4986)
			(layers "F.Cu" "F.Mask" "F.Paste")
			(net "M_H_CPU1_SB_DQS_DP<1>")
		)
		(pad "116" smd rect
			(at -2.050034 39.52494 270)
			(size 0.519938 1.4986)
			(layers "F.Cu" "F.Mask" "F.Paste")
			(net "M_H_CPU1_SB_DQS_DN<1>")
		)
		(pad "117" smd rect
			(at -2.050034 40.375078 270)
			(size 0.519938 1.4986)
			(layers "F.Cu" "F.Mask" "F.Paste")
			(net "GND")
		)
		(pad "118" smd rect
			(at -2.050034 41.224962 270)
			(size 0.519938 1.4986)
			(layers "F.Cu" "F.Mask" "F.Paste")
			(net "M_H_CPU1_SB_DQ<12>")
		)
		(pad "119" smd rect
			(at -2.050034 42.0751 270)
			(size 0.519938 1.4986)
			(layers "F.Cu" "F.Mask" "F.Paste")
			(net "GND")
		)
		(pad "120" smd rect
			(at -2.050034 42.924984 270)
			(size 0.519938 1.4986)
			(layers "F.Cu" "F.Mask" "F.Paste")
			(net "M_H_CPU1_SB_DQ<13>")
		)
		(pad "121" smd rect
			(at -2.050034 43.775122 270)
			(size 0.519938 1.4986)
			(layers "F.Cu" "F.Mask" "F.Paste")
			(net "GND")
		)
		(pad "122" smd rect
			(at -2.050034 44.625006 270)
			(size 0.519938 1.4986)
			(layers "F.Cu" "F.Mask" "F.Paste")
			(net "M_H_CPU1_SB_DQ<16>")
		)
		(pad "123" smd rect
			(at -2.050034 45.47489 270)
			(size 0.519938 1.4986)
			(layers "F.Cu" "F.Mask" "F.Paste")
			(net "GND")
		)
		(pad "124" smd rect
			(at -2.050034 46.325028 270)
			(size 0.519938 1.4986)
			(layers "F.Cu" "F.Mask" "F.Paste")
			(net "M_H_CPU1_SB_DQ<17>")
		)
		(pad "125" smd rect
			(at -2.050034 47.174912 270)
			(size 0.519938 1.4986)
			(layers "F.Cu" "F.Mask" "F.Paste")
			(net "GND")
		)
		(pad "126" smd rect
			(at -2.050034 48.02505 270)
			(size 0.519938 1.4986)
			(layers "F.Cu" "F.Mask" "F.Paste")
			(net "M_H_CPU1_SB_DQS_DP<2>")
		)
		(pad "127" smd rect
			(at -2.050034 48.874934 270)
			(size 0.519938 1.4986)
			(layers "F.Cu" "F.Mask" "F.Paste")
			(net "M_H_CPU1_SB_DQS_DN<2>")
		)
		(pad "128" smd rect
			(at -2.050034 49.725072 270)
			(size 0.519938 1.4986)
			(layers "F.Cu" "F.Mask" "F.Paste")
			(net "GND")
		)
		(pad "129" smd rect
			(at -2.050034 50.574956 270)
			(size 0.519938 1.4986)
			(layers "F.Cu" "F.Mask" "F.Paste")
			(net "M_H_CPU1_SB_DQ<20>")
		)
		(pad "130" smd rect
			(at -2.050034 51.425094 270)
			(size 0.519938 1.4986)
			(layers "F.Cu" "F.Mask" "F.Paste")
			(net "GND")
		)
		(pad "131" smd rect
			(at -2.050034 52.274978 270)
			(size 0.519938 1.4986)
			(layers "F.Cu" "F.Mask" "F.Paste")
			(net "M_H_CPU1_SB_DQ<21>")
		)
		(pad "132" smd rect
			(at -2.050034 53.125116 270)
			(size 0.519938 1.4986)
			(layers "F.Cu" "F.Mask" "F.Paste")
			(net "GND")
		)
		(pad "133" smd rect
			(at -2.050034 53.975 270)
			(size 0.519938 1.4986)
			(layers "F.Cu" "F.Mask" "F.Paste")
			(net "M_H_CPU1_SB_DQ<24>")
		)
		(pad "134" smd rect
			(at -2.050034 54.824884 270)
			(size 0.519938 1.4986)
			(layers "F.Cu" "F.Mask" "F.Paste")
			(net "GND")
		)
		(pad "135" smd rect
			(at -2.050034 55.675022 270)
			(size 0.519938 1.4986)
			(layers "F.Cu" "F.Mask" "F.Paste")
			(net "M_H_CPU1_SB_DQ<25>")
		)
		(pad "136" smd rect
			(at -2.050034 56.524906 270)
			(size 0.519938 1.4986)
			(layers "F.Cu" "F.Mask" "F.Paste")
			(net "GND")
		)
		(pad "137" smd rect
			(at -2.050034 57.375044 270)
			(size 0.519938 1.4986)
			(layers "F.Cu" "F.Mask" "F.Paste")
			(net "M_H_CPU1_SB_DQS_DP<3>")
		)
	)
)
